(kicad_pcb
	(version 20260206)
	(generator "pcbnew")
	(generator_version "10.0")
	(general
		(thickness 1.6)
		(legacy_teardrops no)
	)
	(paper "A4")
	(title_block
		(title "v1-chassis-manager — T6M_CM_d_v01_1031_1645.brd")
		(comment 1 "Open CloudServer (Microsoft) / footprints 716-725 of 2512")
	)
	(layers
		(0 "F.Cu" signal "TOP")
		(4 "In1.Cu" signal "GND1")
		(6 "In2.Cu" signal "IN1")
		(8 "In3.Cu" signal "VCC1")
		(10 "In4.Cu" signal "VCC2")
		(12 "In5.Cu" signal "GND2")
		(14 "In6.Cu" signal "IN2")
		(16 "In7.Cu" signal "IN3")
		(18 "In8.Cu" signal "GND3")
		(2 "B.Cu" signal "BOTTOM")
		(9 "F.Adhes" user "F.Adhesive")
		(11 "B.Adhes" user "B.Adhesive")
		(13 "F.Paste" user "Package Geometry/Pastemask Top")
		(15 "B.Paste" user "Package Geometry/Pastemask Bottom")
		(5 "F.SilkS" user "Ref Des/Silkscreen Top")
		(7 "B.SilkS" user "Ref Des/Silkscreen Bottom")
		(1 "F.Mask" user "Board Geometry/Soldermask Top")
		(3 "B.Mask" user "Board Geometry/Soldermask Bottom")
		(17 "Dwgs.User" user "User.Drawings")
		(19 "Cmts.User" user "User.Comments")
		(21 "Eco1.User" user "User.Eco1")
		(23 "Eco2.User" user "User.Eco2")
		(25 "Edge.Cuts" user "Board Geometry/Outline")
		(27 "Margin" user)
		(31 "F.CrtYd" user "Package Geometry/Place Bound Top")
		(29 "B.CrtYd" user "Package Geometry/Place Bound Bottom")
		(35 "F.Fab" user "Ref Des/Assembly Top")
		(33 "B.Fab" user "Ref Des/Assembly Bottom")
	)
	(footprint ""
		(layer "F.Cu")
		(at 80.24876 -188.126624 90)
		(property "Reference" "C664"
			(at 4.548886 -1.749298 90)
			(unlocked yes)
			(layer "F.SilkS")
			(effects
				(font
					(size 0.7874 0.5842)
					(thickness 0.1524)
				)
				(justify left)
			)
		)
		(property "Value" ""
			(at 0 0 90)
			(layer "F.Fab")
			(effects
				(font
					(size 1.27 1.27)
				)
			)
		)
		(duplicate_pad_numbers_are_jumpers no)
		(fp_line
			(start 0.7874 -0.4064)
			(end 0.7874 0.4064)
			(stroke
				(width 0.1524)
				(type default)
			)
			(layer "F.SilkS")
		)
		(fp_line
			(start -0.7874 -0.4064)
			(end 0.7874 -0.4064)
			(stroke
				(width 0.1524)
				(type default)
			)
			(layer "F.SilkS")
		)
		(fp_line
			(start 0 0.381)
			(end 0 -0.381)
			(stroke
				(width 0.1524)
				(type default)
			)
			(layer "F.SilkS")
		)
		(fp_line
			(start 0.7874 0.4064)
			(end -0.7874 0.4064)
			(stroke
				(width 0.1524)
				(type default)
			)
			(layer "F.SilkS")
		)
		(fp_line
			(start -0.7874 0.4064)
			(end -0.7874 -0.4064)
			(stroke
				(width 0.1524)
				(type default)
			)
			(layer "F.SilkS")
		)
		(fp_poly
			(pts
				(xy -0.5334 0.254) (xy -0.635 0.254) (xy -0.635 0.2286) (xy -0.635 -0.254) (xy -0.5334 -0.254) (xy -0.5334 -0.2794)
				(xy 0.5334 -0.2794) (xy 0.5334 -0.254) (xy 0.635 -0.254) (xy 0.635 0.254) (xy 0.5334 0.254) (xy 0.5334 0.2794)
				(xy -0.508 0.2794) (xy -0.5334 0.2794)
			)
			(stroke
				(width 0)
				(type default)
			)
			(fill no)
			(layer "F.CrtYd")
		)
		(pad "1" smd rect
			(at 0.40005 0 90)
			(size 0.4572 0.508)
			(layers "F.Cu" "F.Mask" "F.Paste")
			(net "T4_NODE3_EN_R")
		)
		(pad "2" smd rect
			(at -0.40005 0 90)
			(size 0.4572 0.508)
			(layers "F.Cu" "F.Mask" "F.Paste")
			(net "GND")
		)
	)
	(footprint ""
		(layer "F.Cu")
		(at 20.915376 -49.716182 90)
		(property "Reference" "U45"
			(at 0.307086 4.860544 0)
			(unlocked yes)
			(layer "F.SilkS")
			(effects
				(font
					(size 0.7874 0.5842)
					(thickness 0.1524)
				)
			)
		)
		(property "Value" ""
			(at 0 0 90)
			(layer "F.Fab")
			(effects
				(font
					(size 1.27 1.27)
				)
			)
		)
		(duplicate_pad_numbers_are_jumpers no)
		(fp_line
			(start 1.651 -1.905)
			(end 1.651 1.905)
			(stroke
				(width 0.1524)
				(type default)
			)
			(layer "F.SilkS")
		)
		(fp_line
			(start -1.651 -1.905)
			(end 1.651 -1.905)
			(stroke
				(width 0.1524)
				(type default)
			)
			(layer "F.SilkS")
		)
		(fp_line
			(start 1.651 1.905)
			(end -1.651 1.905)
			(stroke
				(width 0.1524)
				(type default)
			)
			(layer "F.SilkS")
		)
		(fp_line
			(start -1.651 1.905)
			(end -1.651 -1.905)
			(stroke
				(width 0.1524)
				(type default)
			)
			(layer "F.SilkS")
		)
		(fp_poly
			(pts
				(xy -1.524 0.7112) (xy -1.524 1.7526) (xy -0.508 1.7526) (xy -0.508 0.6985) (xy 0.508 0.6985) (xy 0.508 1.7526)
				(xy 1.524 1.7526) (xy 1.524 0.6985) (xy 1.524 -0.6985) (xy 0.508 -0.6985) (xy 0.508 -1.7526) (xy -0.508 -1.7526)
				(xy -0.508 -0.6985) (xy -1.524 -0.6985) (xy -1.524 0.6985)
			)
			(stroke
				(width 0)
				(type default)
			)
			(fill no)
			(layer "F.CrtYd")
		)
		(fp_text user "3"
			(at 2.001012 -1.593088 90)
			(unlocked yes)
			(layer "F.SilkS")
			(effects
				(font
					(size 0.635 0.4064)
					(thickness 0.1524)
				)
			)
		)
		(fp_text user "2"
			(at 1.420114 2.46888 90)
			(unlocked yes)
			(layer "F.SilkS")
			(effects
				(font
					(size 0.635 0.4064)
					(thickness 0.1524)
				)
			)
		)
		(fp_text user "1"
			(at 0.161798 2.515362 90)
			(unlocked yes)
			(layer "F.SilkS")
			(effects
				(font
					(size 0.635 0.4064)
					(thickness 0.1524)
				)
			)
		)
		(pad "1" smd rect
			(at -1.016 1.1176 90)
			(size 1.016 1.27)
			(layers "F.Cu" "F.Mask" "F.Paste")
			(net "GND")
		)
		(pad "2" smd rect
			(at 1.016 1.1176 90)
			(size 1.016 1.27)
			(layers "F.Cu" "F.Mask" "F.Paste")
			(net "P5V_CRT")
		)
		(pad "3" smd rect
			(at 0 -1.1176 90)
			(size 1.016 1.27)
			(layers "F.Cu" "F.Mask" "F.Paste")
			(net "CRT_G")
		)
	)
	(footprint ""
		(layer "F.Cu")
		(at 57.38876 -188.126624 -90)
		(property "Reference" "R949"
			(at -4.548886 -0.391922 90)
			(unlocked yes)
			(layer "F.SilkS")
			(effects
				(font
					(size 0.7874 0.5842)
					(thickness 0.1524)
				)
				(justify left)
			)
		)
		(property "Value" ""
			(at 0 0 270)
			(layer "F.Fab")
			(effects
				(font
					(size 1.27 1.27)
				)
			)
		)
		(duplicate_pad_numbers_are_jumpers no)
		(fp_line
			(start -0.7874 0.4064)
			(end -0.7874 -0.4064)
			(stroke
				(width 0.1524)
				(type default)
			)
			(layer "F.SilkS")
		)
		(fp_line
			(start 0.7874 0.4064)
			(end -0.7874 0.4064)
			(stroke
				(width 0.1524)
				(type default)
			)
			(layer "F.SilkS")
		)
		(fp_line
			(start -0.7874 -0.4064)
			(end 0.7874 -0.4064)
			(stroke
				(width 0.1524)
				(type default)
			)
			(layer "F.SilkS")
		)
		(fp_line
			(start 0.7874 -0.4064)
			(end 0.7874 0.4064)
			(stroke
				(width 0.1524)
				(type default)
			)
			(layer "F.SilkS")
		)
		(fp_poly
			(pts
				(xy -0.508 0.2794) (xy -0.508 0.2286) (xy -0.635 0.2286) (xy -0.635 -0.254) (xy -0.5334 -0.254)
				(xy -0.5334 -0.2794) (xy 0.5334 -0.2794) (xy 0.5334 -0.254) (xy 0.635 -0.254) (xy 0.635 0.254) (xy 0.5334 0.254)
				(xy 0.5334 0.2794)
			)
			(stroke
				(width 0)
				(type default)
			)
			(fill no)
			(layer "F.CrtYd")
		)
		(pad "1" smd rect
			(at 0.40005 0 270)
			(size 0.4572 0.508)
			(layers "F.Cu" "F.Mask" "F.Paste")
			(net "UART_T2_NODE4_RXD")
		)
		(pad "2" smd rect
			(at -0.40005 0 270)
			(size 0.4572 0.508)
			(layers "F.Cu" "F.Mask" "F.Paste")
			(net "UART_T2_NODE4_RXD_R")
		)
	)
	(footprint ""
		(layer "F.Cu")
		(at 50.75936 -4.347464 90)
		(property "Reference" "PR32"
			(at -0.395224 1.775206 90)
			(unlocked yes)
			(layer "F.SilkS")
			(effects
				(font
					(size 0.7874 0.5842)
					(thickness 0.1524)
				)
				(justify left)
			)
		)
		(property "Value" ""
			(at 0 0 90)
			(layer "F.Fab")
			(effects
				(font
					(size 1.27 1.27)
				)
			)
		)
		(duplicate_pad_numbers_are_jumpers no)
		(fp_line
			(start 2.2098 -0.9398)
			(end 2.2098 0.9398)
			(stroke
				(width 0.1524)
				(type default)
			)
			(layer "F.SilkS")
		)
		(fp_line
			(start -2.2098 -0.9398)
			(end 2.2098 -0.9398)
			(stroke
				(width 0.1524)
				(type default)
			)
			(layer "F.SilkS")
		)
		(fp_line
			(start 2.2098 0.9398)
			(end -2.2098 0.9398)
			(stroke
				(width 0.1524)
				(type default)
			)
			(layer "F.SilkS")
		)
		(fp_line
			(start -2.2098 0.9398)
			(end -2.2098 -0.9398)
			(stroke
				(width 0.1524)
				(type default)
			)
			(layer "F.SilkS")
		)
		(fp_poly
			(pts
				(xy 2.0574 0.8382) (xy 2.0574 -0.8382) (xy 2.0574 -0.9398) (xy -2.0574 -0.9398) (xy -2.0574 -0.8382)
				(xy -2.0574 0.8382) (xy -2.0574 0.9398) (xy 2.0574 0.9398)
			)
			(stroke
				(width 0)
				(type default)
			)
			(fill no)
			(layer "F.CrtYd")
		)
		(pad "1" smd rect
			(at 1.4732 0 90)
			(size 1.1684 1.5748)
			(layers "F.Cu" "F.Mask" "F.Paste")
			(net "SW_PV_VDDR_NODE1_VIN_FLT")
		)
		(pad "2" smd rect
			(at -1.4732 0 90)
			(size 1.1684 1.5748)
			(layers "F.Cu" "F.Mask" "F.Paste")
			(net "P12V_AUX")
		)
	)
	(footprint ""
		(layer "F.Cu")
		(at 151.113998 -156.34843 180)
		(property "Reference" "C436"
			(at -0.933958 1.048258 0)
			(unlocked yes)
			(layer "F.SilkS")
			(effects
				(font
					(size 0.7874 0.5842)
					(thickness 0.1524)
				)
				(justify left)
			)
		)
		(property "Value" ""
			(at 0 0 180)
			(layer "F.Fab")
			(effects
				(font
					(size 1.27 1.27)
				)
			)
		)
		(duplicate_pad_numbers_are_jumpers no)
		(fp_line
			(start 0.7874 0.4064)
			(end -0.7874 0.4064)
			(stroke
				(width 0.1524)
				(type default)
			)
			(layer "F.SilkS")
		)
		(fp_line
			(start 0.7874 -0.4064)
			(end 0.7874 0.4064)
			(stroke
				(width 0.1524)
				(type default)
			)
			(layer "F.SilkS")
		)
		(fp_line
			(start 0 0.381)
			(end 0 -0.381)
			(stroke
				(width 0.1524)
				(type default)
			)
			(layer "F.SilkS")
		)
		(fp_line
			(start -0.7874 0.4064)
			(end -0.7874 -0.4064)
			(stroke
				(width 0.1524)
				(type default)
			)
			(layer "F.SilkS")
		)
		(fp_line
			(start -0.7874 -0.4064)
			(end 0.7874 -0.4064)
			(stroke
				(width 0.1524)
				(type default)
			)
			(layer "F.SilkS")
		)
		(fp_poly
			(pts
				(xy -0.5334 0.254) (xy -0.635 0.254) (xy -0.635 0.2286) (xy -0.635 -0.254) (xy -0.5334 -0.254) (xy -0.5334 -0.2794)
				(xy 0.5334 -0.2794) (xy 0.5334 -0.254) (xy 0.635 -0.254) (xy 0.635 0.254) (xy 0.5334 0.254) (xy 0.5334 0.2794)
				(xy -0.508 0.2794) (xy -0.5334 0.2794)
			)
			(stroke
				(width 0)
				(type default)
			)
			(fill no)
			(layer "F.CrtYd")
		)
		(pad "1" smd rect
			(at 0.40005 0 180)
			(size 0.4572 0.508)
			(layers "F.Cu" "F.Mask" "F.Paste")
			(net "P2E_CPU_NIC2_NODE1_RX_DN")
		)
		(pad "2" smd rect
			(at -0.40005 0 180)
			(size 0.4572 0.508)
			(layers "F.Cu" "F.Mask" "F.Paste")
			(net "PCIE_LAN2_RX_C_DN")
		)
	)
	(footprint ""
		(layer "F.Cu")
		(at 150.47976 -185.205624 -90)
		(property "Reference" "R984"
			(at -4.768088 -0.259588 90)
			(unlocked yes)
			(layer "F.SilkS")
			(effects
				(font
					(size 0.7874 0.5842)
					(thickness 0.1524)
				)
				(justify left)
			)
		)
		(property "Value" ""
			(at 0 0 270)
			(layer "F.Fab")
			(effects
				(font
					(size 1.27 1.27)
				)
			)
		)
		(duplicate_pad_numbers_are_jumpers no)
		(fp_line
			(start -0.7874 0.4064)
			(end -0.7874 -0.4064)
			(stroke
				(width 0.1524)
				(type default)
			)
			(layer "F.SilkS")
		)
		(fp_line
			(start 0.7874 0.4064)
			(end -0.7874 0.4064)
			(stroke
				(width 0.1524)
				(type default)
			)
			(layer "F.SilkS")
		)
		(fp_line
			(start -0.7874 -0.4064)
			(end 0.7874 -0.4064)
			(stroke
				(width 0.1524)
				(type default)
			)
			(layer "F.SilkS")
		)
		(fp_line
			(start 0.7874 -0.4064)
			(end 0.7874 0.4064)
			(stroke
				(width 0.1524)
				(type default)
			)
			(layer "F.SilkS")
		)
		(fp_poly
			(pts
				(xy -0.508 0.2794) (xy -0.508 0.2286) (xy -0.635 0.2286) (xy -0.635 -0.254) (xy -0.5334 -0.254)
				(xy -0.5334 -0.2794) (xy 0.5334 -0.2794) (xy 0.5334 -0.254) (xy 0.635 -0.254) (xy 0.635 0.254) (xy 0.5334 0.254)
				(xy 0.5334 0.2794)
			)
			(stroke
				(width 0)
				(type default)
			)
			(fill no)
			(layer "F.CrtYd")
		)
		(pad "1" smd rect
			(at 0.40005 0 270)
			(size 0.4572 0.508)
			(layers "F.Cu" "F.Mask" "F.Paste")
			(net "UART_T12_NODE1_TXD")
		)
		(pad "2" smd rect
			(at -0.40005 0 270)
			(size 0.4572 0.508)
			(layers "F.Cu" "F.Mask" "F.Paste")
			(net "UART_T12_NODE1_TXD_R")
		)
	)
	(footprint ""
		(layer "F.Cu")
		(at 62.08776 -178.804824 180)
		(property "Reference" "U97"
			(at 11.201908 -132.653786 90)
			(unlocked yes)
			(layer "F.SilkS")
			(effects
				(font
					(size 0.7874 0.5842)
					(thickness 0.1524)
				)
			)
		)
		(property "Value" ""
			(at 0 0 180)
			(layer "F.Fab")
			(effects
				(font
					(size 1.27 1.27)
				)
			)
		)
		(duplicate_pad_numbers_are_jumpers no)
		(fp_line
			(start 1.651 1.905)
			(end -1.651 1.905)
			(stroke
				(width 0.1524)
				(type default)
			)
			(layer "F.SilkS")
		)
		(fp_line
			(start 1.651 -1.905)
			(end 1.651 1.905)
			(stroke
				(width 0.1524)
				(type default)
			)
			(layer "F.SilkS")
		)
		(fp_line
			(start -1.651 1.905)
			(end -1.651 -1.905)
			(stroke
				(width 0.1524)
				(type default)
			)
			(layer "F.SilkS")
		)
		(fp_line
			(start -1.651 -1.905)
			(end 1.651 -1.905)
			(stroke
				(width 0.1524)
				(type default)
			)
			(layer "F.SilkS")
		)
		(fp_poly
			(pts
				(xy -1.524 0.7112) (xy -1.524 1.7526) (xy -0.508 1.7526) (xy -0.508 0.6985) (xy 0.508 0.6985) (xy 0.508 1.7526)
				(xy 1.524 1.7526) (xy 1.524 0.6985) (xy 1.524 -0.6985) (xy 0.508 -0.6985) (xy 0.508 -1.7526) (xy -0.508 -1.7526)
				(xy -0.508 -0.6985) (xy -1.524 -0.6985) (xy -1.524 0.6985)
			)
			(stroke
				(width 0)
				(type default)
			)
			(fill no)
			(layer "F.CrtYd")
		)
		(fp_text user "S"
			(at 0.762508 2.487168 0)
			(unlocked yes)
			(layer "F.SilkS")
			(effects
				(font
					(size 0.635 0.4064)
					(thickness 0.1524)
				)
			)
		)
		(fp_text user "D"
			(at 0.095758 -2.441956 0)
			(unlocked yes)
			(layer "F.SilkS")
			(effects
				(font
					(size 0.635 0.4064)
					(thickness 0.1524)
				)
			)
		)
		(fp_text user "G"
			(at -0.380492 2.487168 0)
			(unlocked yes)
			(layer "F.SilkS")
			(effects
				(font
					(size 0.635 0.4064)
					(thickness 0.1524)
				)
			)
		)
		(pad "D" smd rect
			(at 0 -1.1176 180)
			(size 1.016 1.27)
			(layers "F.Cu" "F.Mask" "F.Paste")
			(net "PSU_DC_OK_N")
		)
		(pad "G" smd rect
			(at -1.016 1.1176 180)
			(size 1.016 1.27)
			(layers "F.Cu" "F.Mask" "F.Paste")
			(net "PSU2_DC_OK_R_BUF")
		)
		(pad "S" smd rect
			(at 1.016 1.1176 180)
			(size 1.016 1.27)
			(layers "F.Cu" "F.Mask" "F.Paste")
			(net "GND")
		)
	)
	(footprint ""
		(layer "F.Cu")
		(at 71.116698 -17.679416 90)
		(property "Reference" "C160"
			(at -4.797552 6.316472 90)
			(unlocked yes)
			(layer "F.SilkS")
			(effects
				(font
					(size 0.7874 0.5842)
					(thickness 0.1524)
				)
				(justify left)
			)
		)
		(property "Value" ""
			(at 0 0 90)
			(layer "F.Fab")
			(effects
				(font
					(size 1.27 1.27)
				)
			)
		)
		(duplicate_pad_numbers_are_jumpers no)
		(fp_line
			(start 0.7874 -0.4064)
			(end 0.7874 0.4064)
			(stroke
				(width 0.1524)
				(type default)
			)
			(layer "F.SilkS")
		)
		(fp_line
			(start -0.7874 -0.4064)
			(end 0.7874 -0.4064)
			(stroke
				(width 0.1524)
				(type default)
			)
			(layer "F.SilkS")
		)
		(fp_line
			(start 0 0.381)
			(end 0 -0.381)
			(stroke
				(width 0.1524)
				(type default)
			)
			(layer "F.SilkS")
		)
		(fp_line
			(start 0.7874 0.4064)
			(end -0.7874 0.4064)
			(stroke
				(width 0.1524)
				(type default)
			)
			(layer "F.SilkS")
		)
		(fp_line
			(start -0.7874 0.4064)
			(end -0.7874 -0.4064)
			(stroke
				(width 0.1524)
				(type default)
			)
			(layer "F.SilkS")
		)
		(fp_poly
			(pts
				(xy -0.5334 0.254) (xy -0.635 0.254) (xy -0.635 0.2286) (xy -0.635 -0.254) (xy -0.5334 -0.254) (xy -0.5334 -0.2794)
				(xy 0.5334 -0.2794) (xy 0.5334 -0.254) (xy 0.635 -0.254) (xy 0.635 0.254) (xy 0.5334 0.254) (xy 0.5334 0.2794)
				(xy -0.508 0.2794) (xy -0.5334 0.2794)
			)
			(stroke
				(width 0)
				(type default)
			)
			(fill no)
			(layer "F.CrtYd")
		)
		(pad "1" smd rect
			(at 0.40005 0 90)
			(size 0.4572 0.508)
			(layers "F.Cu" "F.Mask" "F.Paste")
			(net "PV_VDDR_NODE1")
		)
		(pad "2" smd rect
			(at -0.40005 0 90)
			(size 0.4572 0.508)
			(layers "F.Cu" "F.Mask" "F.Paste")
			(net "GND")
		)
	)
	(footprint ""
		(layer "F.Cu")
		(at 51.67376 -182.238142 90)
		(property "Reference" "C602"
			(at -133.313932 -3.637788 90)
			(unlocked yes)
			(layer "F.SilkS")
			(effects
				(font
					(size 0.7874 0.5842)
					(thickness 0.1524)
				)
				(justify left)
			)
		)
		(property "Value" ""
			(at 0 0 90)
			(layer "F.Fab")
			(effects
				(font
					(size 1.27 1.27)
				)
			)
		)
		(duplicate_pad_numbers_are_jumpers no)
		(fp_line
			(start 0.7874 -0.4064)
			(end 0.7874 0.4064)
			(stroke
				(width 0.1524)
				(type default)
			)
			(layer "F.SilkS")
		)
		(fp_line
			(start -0.7874 -0.4064)
			(end 0.7874 -0.4064)
			(stroke
				(width 0.1524)
				(type default)
			)
			(layer "F.SilkS")
		)
		(fp_line
			(start 0 0.381)
			(end 0 -0.381)
			(stroke
				(width 0.1524)
				(type default)
			)
			(layer "F.SilkS")
		)
		(fp_line
			(start 0.7874 0.4064)
			(end -0.7874 0.4064)
			(stroke
				(width 0.1524)
				(type default)
			)
			(layer "F.SilkS")
		)
		(fp_line
			(start -0.7874 0.4064)
			(end -0.7874 -0.4064)
			(stroke
				(width 0.1524)
				(type default)
			)
			(layer "F.SilkS")
		)
		(fp_poly
			(pts
				(xy -0.5334 0.254) (xy -0.635 0.254) (xy -0.635 0.2286) (xy -0.635 -0.254) (xy -0.5334 -0.254) (xy -0.5334 -0.2794)
				(xy 0.5334 -0.2794) (xy 0.5334 -0.254) (xy 0.635 -0.254) (xy 0.635 0.254) (xy 0.5334 0.254) (xy 0.5334 0.2794)
				(xy -0.508 0.2794) (xy -0.5334 0.2794)
			)
			(stroke
				(width 0)
				(type default)
			)
			(fill no)
			(layer "F.CrtYd")
		)
		(pad "1" smd rect
			(at 0.40005 0 90)
			(size 0.4572 0.508)
			(layers "F.Cu" "F.Mask" "F.Paste")
			(net "PSU2_AC_OK")
		)
		(pad "2" smd rect
			(at -0.40005 0 90)
			(size 0.4572 0.508)
			(layers "F.Cu" "F.Mask" "F.Paste")
			(net "GND")
		)
	)
	(footprint ""
		(layer "F.Cu")
		(at 74.53376 -185.205624 -90)
		(property "Reference" "R941"
			(at -4.006088 1.302258 90)
			(unlocked yes)
			(layer "F.SilkS")
			(effects
				(font
					(size 0.7874 0.5842)
					(thickness 0.1524)
				)
				(justify left)
			)
		)
		(property "Value" ""
			(at 0 0 270)
			(layer "F.Fab")
			(effects
				(font
					(size 1.27 1.27)
				)
			)
		)
		(duplicate_pad_numbers_are_jumpers no)
		(fp_line
			(start -0.7874 0.4064)
			(end -0.7874 -0.4064)
			(stroke
				(width 0.1524)
				(type default)
			)
			(layer "F.SilkS")
		)
		(fp_line
			(start 0.7874 0.4064)
			(end -0.7874 0.4064)
			(stroke
				(width 0.1524)
				(type default)
			)
			(layer "F.SilkS")
		)
		(fp_line
			(start -0.7874 -0.4064)
			(end 0.7874 -0.4064)
			(stroke
				(width 0.1524)
				(type default)
			)
			(layer "F.SilkS")
		)
		(fp_line
			(start 0.7874 -0.4064)
			(end 0.7874 0.4064)
			(stroke
				(width 0.1524)
				(type default)
			)
			(layer "F.SilkS")
		)
		(fp_poly
			(pts
				(xy -0.508 0.2794) (xy -0.508 0.2286) (xy -0.635 0.2286) (xy -0.635 -0.254) (xy -0.5334 -0.254)
				(xy -0.5334 -0.2794) (xy 0.5334 -0.2794) (xy 0.5334 -0.254) (xy 0.635 -0.254) (xy 0.635 0.254) (xy 0.5334 0.254)
				(xy 0.5334 0.2794)
			)
			(stroke
				(width 0)
				(type default)
			)
			(fill no)
			(layer "F.CrtYd")
		)
		(pad "1" smd rect
			(at 0.40005 0 270)
			(size 0.4572 0.508)
			(layers "F.Cu" "F.Mask" "F.Paste")
			(net "UART_T4_NODE2_TXD")
		)
		(pad "2" smd rect
			(at -0.40005 0 270)
			(size 0.4572 0.508)
			(layers "F.Cu" "F.Mask" "F.Paste")
			(net "UART_T4_NODE2_TXD_R")
		)
	)
)
